# BASEBOARD_FAB2 (Tioga Pass) — schematic netlist excerpt (pin names and nets, part order shuffled) for the footprints in the layout excerpt that follows; sources: Cadence DE-HDL packaged netlist, KiCad conversion of Wiwynn_Tioga_Pass_MB.brd

EU8F1  RT8240  IC  pkg QFN  page 240
  LGATE  = VR_P3V3_STBY_LGATE
  PHASE  = VR_P3V3_STBY_PHASE
  UGATE  = VR_P3V3_STBY_UGATE
  BOOT  = VR_P3V3_STBY_BOOT
  VCC  = P5V_STBY
  VOUT  = VSENSE_VOUT_P3V3_STBY
  RGND  = VSENSE_RGND_P3V3_STBY
  EN  = VR_P3V3_STBY_EN
  PGOOD  = PWRGD_P3V3_STBY_R
  CS  = VR_P3V3_STBY_OCSELECT
  G0  = AGND_P3V3_STBY
  GND(0)  = AGND_P3V3_STBY
  GND(1)  = AGND_P3V3_STBY

(kicad_pcb
	(version 20260206)
	(generator "pcbnew")
	(generator_version "10.0")
	(general
		(thickness 1.6)
		(legacy_teardrops no)
	)
	(paper "A4")
	(title_block
		(title "Wiwynn_Tioga_Pass_MB.brd")
		(comment 1 "Tioga Pass / footprints 1292-1292 of 4770")
	)
	(layers
		(0 "F.Cu" signal "TOP")
		(4 "In1.Cu" signal "L2GND")
		(6 "In2.Cu" signal "L3")
		(8 "In3.Cu" signal "L4GND")
		(10 "In4.Cu" signal "L5")
		(12 "In5.Cu" signal "L6GND")
		(14 "In6.Cu" signal "L7VCC")
		(16 "In7.Cu" signal "L8VCC")
		(18 "In8.Cu" signal "L9GND")
		(20 "In9.Cu" signal "L10")
		(22 "In10.Cu" signal "L11GND")
		(24 "In11.Cu" signal "L12")
		(26 "In12.Cu" signal "L13GND")
		(2 "B.Cu" signal "BOTTOM")
		(9 "F.Adhes" user "F.Adhesive")
		(11 "B.Adhes" user "B.Adhesive")
		(13 "F.Paste" user "Package Geometry/Pastemask Top")
		(15 "B.Paste" user "Package Geometry/Pastemask Bottom")
		(5 "F.SilkS" user "Ref Des/Silkscreen Top")
		(7 "B.SilkS" user "Ref Des/Silkscreen Bottom")
		(1 "F.Mask" user "Board Geometry/Soldermask Top")
		(3 "B.Mask" user "Board Geometry/Soldermask Bottom")
		(17 "Dwgs.User" user "User.Drawings")
		(19 "Cmts.User" user "User.Comments")
		(21 "Eco1.User" user "User.Eco1")
		(23 "Eco2.User" user "User.Eco2")
		(25 "Edge.Cuts" user "Board Geometry/Outline")
		(27 "Margin" user)
		(31 "F.CrtYd" user "Package Geometry/Place Bound Top")
		(29 "B.CrtYd" user "Package Geometry/Place Bound Bottom")
		(35 "F.Fab" user "Ref Des/Assembly Top")
		(33 "B.Fab" user "Ref Des/Assembly Bottom")
	)
	(footprint ""
		(layer "F.Cu")
		(at 467.9315 -23.0505 180)
		(property "Reference" "EU8F1"
			(at -2.56667 -0.254 90)
			(unlocked yes)
			(layer "F.SilkS")
			(effects
				(font
					(size 0.7874 0.5842)
					(thickness 0.1524)
				)
			)
		)
		(property "Value" ""
			(at 0 0 180)
			(layer "F.Fab")
			(effects
				(font
					(size 1.27 1.27)
				)
			)
		)
		(duplicate_pad_numbers_are_jumpers no)
		(fp_line
			(start 1.050036 0.834898)
			(end 1.050036 1.050036)
			(stroke
				(width 0.1524)
				(type default)
			)
			(layer "F.SilkS")
		)
		(fp_line
			(start 1.050036 -0.834898)
			(end 1.050036 -1.050036)
			(stroke
				(width 0.1524)
				(type default)
			)
			(layer "F.SilkS")
		)
		(fp_line
			(start 0.834898 1.050036)
			(end 1.050036 1.050036)
			(stroke
				(width 0.1524)
				(type default)
			)
			(layer "F.SilkS")
		)
		(fp_line
			(start 0.834898 -1.050036)
			(end 1.050036 -1.050036)
			(stroke
				(width 0.1524)
				(type default)
			)
			(layer "F.SilkS")
		)
		(fp_line
			(start -0.834898 1.050036)
			(end -1.050036 1.050036)
			(stroke
				(width 0.1524)
				(type default)
			)
			(layer "F.SilkS")
		)
		(fp_line
			(start -0.834898 -1.050036)
			(end -1.050036 -1.050036)
			(stroke
				(width 0.1524)
				(type default)
			)
			(layer "F.SilkS")
		)
		(fp_line
			(start -1.050036 0.834898)
			(end -1.050036 1.050036)
			(stroke
				(width 0.1524)
				(type default)
			)
			(layer "F.SilkS")
		)
		(fp_line
			(start -1.050036 -0.834898)
			(end -1.050036 -1.050036)
			(stroke
				(width 0.1524)
				(type default)
			)
			(layer "F.SilkS")
		)
		(fp_circle
			(center -1.675892 -0.964438)
			(end -1.802638 -0.964438)
			(stroke
				(width 0.254)
				(type default)
			)
			(fill no)
			(layer "F.SilkS")
		)
		(fp_rect
			(start 0.4445 -0.4445)
			(end -0.4445 0.4445)
			(stroke
				(width 0)
				(type default)
			)
			(fill yes)
			(layer "F.Paste")
		)
		(fp_rect
			(start 1.050036 -1.050036)
			(end -1.050036 1.050036)
			(stroke
				(width 0)
				(type default)
			)
			(fill no)
			(layer "F.CrtYd")
		)
		(fp_line
			(start 1.050036 1.050036)
			(end -1.050036 1.050036)
			(stroke
				(width 0.1)
				(type default)
			)
			(layer "F.Fab")
		)
		(fp_line
			(start 1.050036 -1.050036)
			(end 1.050036 1.050036)
			(stroke
				(width 0.1)
				(type default)
			)
			(layer "F.Fab")
		)
		(fp_line
			(start -1.050036 1.050036)
			(end -1.050036 -1.050036)
			(stroke
				(width 0.1)
				(type default)
			)
			(layer "F.Fab")
		)
		(fp_line
			(start -1.050036 -1.050036)
			(end 1.050036 -1.050036)
			(stroke
				(width 0.1)
				(type default)
			)
			(layer "F.Fab")
		)
		(fp_circle
			(center -1.675892 -0.964438)
			(end -1.802638 -0.964438)
			(stroke
				(width 0.254)
				(type default)
			)
			(fill no)
			(layer "F.Fab")
		)
		(pad "1" smd custom
			(at -0.9779 -0.40005 180)
			(size 0.0508 0.0508)
			(layers "F.Cu" "F.Mask" "F.Paste")
			(net "VR_P3V3_STBY_LGATE")
			(options
				(clearance outline)
				(anchor circle)
			)
			(primitives
				(gr_poly
					(pts
						(xy -0.3302 0.1016) (xy -0.3302 -0.1016)
						(arc
							(start 0.2286 -0.1016)
							(mid 0.3302 0)
							(end 0.2286 0.1016)
						)
					)
					(width 0)
					(fill yes)
				)
			)
		)
		(pad "2" smd custom
			(at -0.9779 0 180)
			(size 0.0508 0.0508)
			(layers "F.Cu" "F.Mask" "F.Paste")
			(net "VR_P3V3_STBY_PHASE")
			(options
				(clearance outline)
				(anchor circle)
			)
			(primitives
				(gr_poly
					(pts
						(xy -0.3302 0.1016) (xy -0.3302 -0.1016)
						(arc
							(start 0.2286 -0.1016)
							(mid 0.3302 0)
							(end 0.2286 0.1016)
						)
					)
					(width 0)
					(fill yes)
				)
			)
		)
		(pad "3" smd custom
			(at -0.9779 0.40005 180)
			(size 0.0508 0.0508)
			(layers "F.Cu" "F.Mask" "F.Paste")
			(net "VR_P3V3_STBY_UGATE")
			(options
				(clearance outline)
				(anchor circle)
			)
			(primitives
				(gr_poly
					(pts
						(xy -0.3302 0.1016) (xy -0.3302 -0.1016)
						(arc
							(start 0.2286 -0.1016)
							(mid 0.3302 0)
							(end 0.2286 0.1016)
						)
					)
					(width 0)
					(fill yes)
				)
			)
		)
		(pad "4" smd custom
			(at -0.40005 0.9779 180)
			(size 0.0508 0.0508)
			(layers "F.Cu" "F.Mask" "F.Paste")
			(net "VR_P3V3_STBY_BOOT")
			(options
				(clearance outline)
				(anchor circle)
			)
			(primitives
				(gr_poly
					(pts
						(xy 0.1016 0.3302) (xy -0.1016 0.3302)
						(arc
							(start -0.1016 -0.2286)
							(mid 0 -0.3302)
							(end 0.1016 -0.2286)
						)
					)
					(width 0)
					(fill yes)
				)
			)
		)
		(pad "5" smd custom
			(at 0 0.9779 180)
			(size 0.0508 0.0508)
			(layers "F.Cu" "F.Mask" "F.Paste")
			(net "P5V_STBY")
			(options
				(clearance outline)
				(anchor circle)
			)
			(primitives
				(gr_poly
					(pts
						(xy 0.1016 0.3302) (xy -0.1016 0.3302)
						(arc
							(start -0.1016 -0.2286)
							(mid 0 -0.3302)
							(end 0.1016 -0.2286)
						)
					)
					(width 0)
					(fill yes)
				)
			)
		)
		(pad "6" smd custom
			(at 0.40005 0.9779 180)
			(size 0.0508 0.0508)
			(layers "F.Cu" "F.Mask" "F.Paste")
			(net "VSENSE_VOUT_P3V3_STBY")
			(options
				(clearance outline)
				(anchor circle)
			)
			(primitives
				(gr_poly
					(pts
						(xy 0.1016 0.3302) (xy -0.1016 0.3302)
						(arc
							(start -0.1016 -0.2286)
							(mid 0 -0.3302)
							(end 0.1016 -0.2286)
						)
					)
					(width 0)
					(fill yes)
				)
			)
		)
		(pad "7" smd custom
			(at 0.9779 0.40005 180)
			(size 0.0508 0.0508)
			(layers "F.Cu" "F.Mask" "F.Paste")
			(net "VSENSE_RGND_P3V3_STBY")
			(options
				(clearance outline)
				(anchor circle)
			)
			(primitives
				(gr_poly
					(pts
						(xy 0.3302 -0.1016) (xy 0.3302 0.1016)
						(arc
							(start -0.2286 0.1016)
							(mid -0.3302 0)
							(end -0.2286 -0.1016)
						)
					)
					(width 0)
					(fill yes)
				)
			)
		)
		(pad "8" smd custom
			(at 0.9779 0 180)
			(size 0.0508 0.0508)
			(layers "F.Cu" "F.Mask" "F.Paste")
			(net "VR_P3V3_STBY_EN")
			(options
				(clearance outline)
				(anchor circle)
			)
			(primitives
				(gr_poly
					(pts
						(xy 0.3302 -0.1016) (xy 0.3302 0.1016)
						(arc
							(start -0.2286 0.1016)
							(mid -0.3302 0)
							(end -0.2286 -0.1016)
						)
					)
					(width 0)
					(fill yes)
				)
			)
		)
		(pad "9" smd custom
			(at 0.9779 -0.40005 180)
			(size 0.0508 0.0508)
			(layers "F.Cu" "F.Mask" "F.Paste")
			(net "PWRGD_P3V3_STBY_R")
			(options
				(clearance outline)
				(anchor circle)
			)
			(primitives
				(gr_poly
					(pts
						(xy 0.3302 -0.1016) (xy 0.3302 0.1016)
						(arc
							(start -0.2286 0.1016)
							(mid -0.3302 0)
							(end -0.2286 -0.1016)
						)
					)
					(width 0)
					(fill yes)
				)
			)
		)
		(pad "10" smd custom
			(at 0.40005 -0.9779 180)
			(size 0.0508 0.0508)
			(layers "F.Cu" "F.Mask" "F.Paste")
			(net "VR_P3V3_STBY_OCSELECT")
			(options
				(clearance outline)
				(anchor circle)
			)
			(primitives
				(gr_poly
					(pts
						(xy -0.1016 -0.3302) (xy 0.1016 -0.3302)
						(arc
							(start 0.1016 0.2286)
							(mid 0 0.3302)
							(end -0.1016 0.2286)
						)
					)
					(width 0)
					(fill yes)
				)
			)
		)
		(pad "11" smd custom
			(at 0 -0.9779 180)
			(size 0.0508 0.0508)
			(layers "F.Cu" "F.Mask" "F.Paste")
			(net "AGND_P3V3_STBY")
			(options
				(clearance outline)
				(anchor circle)
			)
			(primitives
				(gr_poly
					(pts
						(xy -0.1016 -0.3302) (xy 0.1016 -0.3302)
						(arc
							(start 0.1016 0.2286)
							(mid 0 0.3302)
							(end -0.1016 0.2286)
						)
					)
					(width 0)
					(fill yes)
				)
			)
		)
		(pad "12" smd custom
			(at -0.40005 -0.9779 180)
			(size 0.0508 0.0508)
			(layers "F.Cu" "F.Mask" "F.Paste")
			(net "AGND_P3V3_STBY")
			(options
				(clearance outline)
				(anchor circle)
			)
			(primitives
				(gr_poly
					(pts
						(xy -0.1016 -0.3302) (xy 0.1016 -0.3302)
						(arc
							(start 0.1016 0.2286)
							(mid 0 0.3302)
							(end -0.1016 0.2286)
						)
					)
					(width 0)
					(fill yes)
				)
			)
		)
		(pad "13" smd rect
			(at 0 0 180)
			(size 0.889 0.889)
			(layers "F.Cu" "F.Mask" "F.Paste")
			(net "AGND_P3V3_STBY")
		)
	)
)
